# BASEBOARD_FAB2 (Tioga Pass) — schematic netlist excerpt (pin names and nets, part order shuffled) for the footprints in the layout excerpt that follows; sources: Cadence DE-HDL packaged netlist, KiCad conversion of Wiwynn_Tioga_Pass_MB.brd

R8A14  RES  150.0 1% CHIP  pkg 0402  page 112 : A = P1V05_PCH_STBY ; B = XDP_TMS
C8B1  CAP_A  22.0UF 4V 20% X6S  pkg 0603V  page 130 : A = P1V8_PCH_STBY ; B = GND
R4G4  RES  0.0 5% CHIP  pkg 0402  page 233 : A = FM_PVPP_CPU1_EN ; B = FM_PVPP_PVDDQ_CPU1_EN_GHJ

(kicad_pcb
	(version 20260206)
	(generator "pcbnew")
	(generator_version "10.0")
	(general
		(thickness 1.6)
		(legacy_teardrops no)
	)
	(paper "A4")
	(title_block
		(title "Wiwynn_Tioga_Pass_MB.brd")
		(comment 1 "Tioga Pass / footprints 55-57 of 4770")
	)
	(layers
		(0 "F.Cu" signal "TOP")
		(4 "In1.Cu" signal "L2GND")
		(6 "In2.Cu" signal "L3")
		(8 "In3.Cu" signal "L4GND")
		(10 "In4.Cu" signal "L5")
		(12 "In5.Cu" signal "L6GND")
		(14 "In6.Cu" signal "L7VCC")
		(16 "In7.Cu" signal "L8VCC")
		(18 "In8.Cu" signal "L9GND")
		(20 "In9.Cu" signal "L10")
		(22 "In10.Cu" signal "L11GND")
		(24 "In11.Cu" signal "L12")
		(26 "In12.Cu" signal "L13GND")
		(2 "B.Cu" signal "BOTTOM")
		(9 "F.Adhes" user "F.Adhesive")
		(11 "B.Adhes" user "B.Adhesive")
		(13 "F.Paste" user "Package Geometry/Pastemask Top")
		(15 "B.Paste" user "Package Geometry/Pastemask Bottom")
		(5 "F.SilkS" user "Ref Des/Silkscreen Top")
		(7 "B.SilkS" user "Ref Des/Silkscreen Bottom")
		(1 "F.Mask" user "Board Geometry/Soldermask Top")
		(3 "B.Mask" user "Board Geometry/Soldermask Bottom")
		(17 "Dwgs.User" user "User.Drawings")
		(19 "Cmts.User" user "User.Comments")
		(21 "Eco1.User" user "User.Eco1")
		(23 "Eco2.User" user "User.Eco2")
		(25 "Edge.Cuts" user "Board Geometry/Outline")
		(27 "Margin" user)
		(31 "F.CrtYd" user "Package Geometry/Place Bound Top")
		(29 "B.CrtYd" user "Package Geometry/Place Bound Bottom")
		(35 "F.Fab" user "Ref Des/Assembly Top")
		(33 "B.Fab" user "Ref Des/Assembly Bottom")
	)
	(footprint ""
		(layer "F.Cu")
		(at 171.6532 -8.6868 90)
		(property "Reference" "R4G4"
			(at 0 0 90)
			(layer "F.SilkS")
			(hide yes)
			(effects
				(font
					(size 1.27 1.27)
				)
			)
		)
		(property "Value" ""
			(at 0 0 90)
			(layer "F.Fab")
			(effects
				(font
					(size 1.27 1.27)
				)
			)
		)
		(duplicate_pad_numbers_are_jumpers no)
		(fp_poly
			(pts
				(xy -0.2794 -0.1016) (xy 0.2794 -0.1016) (xy 0.2794 0.9906) (xy -0.2794 0.9906)
			)
			(stroke
				(width 0)
				(type default)
			)
			(fill no)
			(layer "F.CrtYd")
		)
		(fp_line
			(start 0.2794 -0.1016)
			(end -0.2794 -0.1016)
			(stroke
				(width 0.1)
				(type default)
			)
			(layer "F.Fab")
		)
		(fp_line
			(start -0.2794 -0.1016)
			(end -0.2794 0.9906)
			(stroke
				(width 0.1)
				(type default)
			)
			(layer "F.Fab")
		)
		(fp_line
			(start 0.2794 0.9906)
			(end 0.2794 -0.1016)
			(stroke
				(width 0.1)
				(type default)
			)
			(layer "F.Fab")
		)
		(fp_line
			(start -0.2794 0.9906)
			(end 0.2794 0.9906)
			(stroke
				(width 0.1)
				(type default)
			)
			(layer "F.Fab")
		)
		(pad "1" smd rect
			(at 0 0 90)
			(size 0.508 0.508)
			(layers "F.Cu" "F.Mask" "F.Paste")
			(net "FM_PVPP_CPU1_EN")
		)
		(pad "2" smd rect
			(at 0 0.889 90)
			(size 0.508 0.508)
			(layers "F.Cu" "F.Mask" "F.Paste")
			(net "FM_PVPP_PVDDQ_CPU1_EN_GHJ")
		)
		(zone
			(layer "F.Cu")
			(hatch none 0.5)
			(connect_pads
				(clearance 0)
			)
			(min_thickness 0.25)
			(keepout
				(tracks allowed)
				(vias not_allowed)
				(pads allowed)
				(copperpour not_allowed)
				(footprints allowed)
			)
			(placement
				(enabled no)
				(sheetname "")
			)
			(fill
				(thermal_gap 0.5)
				(thermal_bridge_width 0.5)
				(island_removal_mode 0)
			)
			(polygon
				(pts
					(xy 171.9072 -8.4328) (xy 171.9072 -8.9408) (xy 172.2882 -8.9408) (xy 172.2882 -8.4328)
				)
			)
		)
		(zone
			(layer "F.Cu")
			(hatch none 0.5)
			(connect_pads
				(clearance 0)
			)
			(min_thickness 0.25)
			(keepout
				(tracks not_allowed)
				(vias allowed)
				(pads allowed)
				(copperpour not_allowed)
				(footprints allowed)
			)
			(placement
				(enabled no)
				(sheetname "")
			)
			(fill
				(thermal_gap 0.5)
				(thermal_bridge_width 0.5)
				(island_removal_mode 0)
			)
			(polygon
				(pts
					(xy 172.2882 -8.4328) (xy 172.2882 -8.9408) (xy 171.9072 -8.9408) (xy 171.9072 -8.4328)
				)
			)
		)
	)
	(footprint ""
		(layer "F.Cu")
		(at 414.410652 -135.636)
		(property "Reference" "R8A14"
			(at 0 0 0)
			(layer "F.SilkS")
			(hide yes)
			(effects
				(font
					(size 1.27 1.27)
				)
			)
		)
		(property "Value" ""
			(at 0 0 0)
			(layer "F.Fab")
			(effects
				(font
					(size 1.27 1.27)
				)
			)
		)
		(duplicate_pad_numbers_are_jumpers no)
		(fp_poly
			(pts
				(xy -0.2794 -0.1016) (xy 0.2794 -0.1016) (xy 0.2794 0.9906) (xy -0.2794 0.9906)
			)
			(stroke
				(width 0)
				(type default)
			)
			(fill no)
			(layer "F.CrtYd")
		)
		(fp_line
			(start -0.2794 -0.1016)
			(end -0.2794 0.9906)
			(stroke
				(width 0.1)
				(type default)
			)
			(layer "F.Fab")
		)
		(fp_line
			(start -0.2794 0.9906)
			(end 0.2794 0.9906)
			(stroke
				(width 0.1)
				(type default)
			)
			(layer "F.Fab")
		)
		(fp_line
			(start 0.2794 -0.1016)
			(end -0.2794 -0.1016)
			(stroke
				(width 0.1)
				(type default)
			)
			(layer "F.Fab")
		)
		(fp_line
			(start 0.2794 0.9906)
			(end 0.2794 -0.1016)
			(stroke
				(width 0.1)
				(type default)
			)
			(layer "F.Fab")
		)
		(pad "1" smd rect
			(at 0 0)
			(size 0.508 0.508)
			(layers "F.Cu" "F.Mask" "F.Paste")
			(net "P1V05_PCH_STBY")
		)
		(pad "2" smd rect
			(at 0 0.889)
			(size 0.508 0.508)
			(layers "F.Cu" "F.Mask" "F.Paste")
			(net "XDP_TMS")
		)
		(zone
			(layer "F.Cu")
			(hatch none 0.5)
			(connect_pads
				(clearance 0)
			)
			(min_thickness 0.25)
			(keepout
				(tracks allowed)
				(vias not_allowed)
				(pads allowed)
				(copperpour not_allowed)
				(footprints allowed)
			)
			(placement
				(enabled no)
				(sheetname "")
			)
			(fill
				(thermal_gap 0.5)
				(thermal_bridge_width 0.5)
				(island_removal_mode 0)
			)
			(polygon
				(pts
					(xy 414.156652 -135.382) (xy 414.664652 -135.382) (xy 414.664652 -135.001) (xy 414.156652 -135.001)
				)
			)
		)
		(zone
			(layer "F.Cu")
			(hatch none 0.5)
			(connect_pads
				(clearance 0)
			)
			(min_thickness 0.25)
			(keepout
				(tracks not_allowed)
				(vias allowed)
				(pads allowed)
				(copperpour not_allowed)
				(footprints allowed)
			)
			(placement
				(enabled no)
				(sheetname "")
			)
			(fill
				(thermal_gap 0.5)
				(thermal_bridge_width 0.5)
				(island_removal_mode 0)
			)
			(polygon
				(pts
					(xy 414.156652 -135.001) (xy 414.664652 -135.001) (xy 414.664652 -135.382) (xy 414.156652 -135.382)
				)
			)
		)
	)
	(footprint ""
		(layer "F.Cu")
		(at 406.273 -128.3335)
		(property "Reference" "C8B1"
			(at 0 0 0)
			(layer "F.SilkS")
			(hide yes)
			(effects
				(font
					(size 1.27 1.27)
				)
			)
		)
		(property "Value" ""
			(at 0 0 0)
			(layer "F.Fab")
			(effects
				(font
					(size 1.27 1.27)
				)
			)
		)
		(duplicate_pad_numbers_are_jumpers no)
		(fp_poly
			(pts
				(xy -0.4953 -0.2032) (xy 0.4953 -0.2032) (xy 0.4953 1.6002) (xy -0.4953 1.6002)
			)
			(stroke
				(width 0)
				(type default)
			)
			(fill no)
			(layer "F.CrtYd")
		)
		(fp_line
			(start -0.4953 -0.2032)
			(end 0.4953 -0.2032)
			(stroke
				(width 0.1)
				(type default)
			)
			(layer "F.Fab")
		)
		(fp_line
			(start -0.4953 1.6002)
			(end -0.4953 -0.2032)
			(stroke
				(width 0.1)
				(type default)
			)
			(layer "F.Fab")
		)
		(fp_line
			(start 0.4953 -0.2032)
			(end 0.4953 1.6002)
			(stroke
				(width 0.1)
				(type default)
			)
			(layer "F.Fab")
		)
		(fp_line
			(start 0.4953 1.6002)
			(end -0.4953 1.6002)
			(stroke
				(width 0.1)
				(type default)
			)
			(layer "F.Fab")
		)
		(pad "1" smd rect
			(at 0 0)
			(size 0.762 0.889)
			(layers "F.Cu" "F.Mask" "F.Paste")
			(net "P1V8_PCH_STBY")
		)
		(pad "2" smd rect
			(at 0 1.397)
			(size 0.762 0.889)
			(layers "F.Cu" "F.Mask" "F.Paste")
			(net "GND")
		)
		(zone
			(layer "F.Cu")
			(hatch none 0.5)
			(connect_pads
				(clearance 0)
			)
			(min_thickness 0.25)
			(keepout
				(tracks not_allowed)
				(vias allowed)
				(pads allowed)
				(copperpour not_allowed)
				(footprints allowed)
			)
			(placement
				(enabled no)
				(sheetname "")
			)
			(fill
				(thermal_gap 0.5)
				(thermal_bridge_width 0.5)
				(island_removal_mode 0)
			)
			(polygon
				(pts
					(xy 405.892 -127.889) (xy 406.654 -127.889) (xy 406.654 -127.381) (xy 405.892 -127.381)
				)
			)
		)
	)
)
